(kicad_pcb
	(version 20260206)
	(generator "pcbnew")
	(generator_version "10.0")
	(general
		(thickness 1.6)
		(legacy_teardrops no)
	)
	(paper "A4")
	(title_block
		(title "03242023_DA0F0TMBIJ0_F0T_Motherboard_J_brd_V01_OCP.brd")
		(comment 1 "Grand Teton / footprints 4134-4140 of 6105")
	)
	(layers
		(0 "F.Cu" signal "TOP")
		(4 "In1.Cu" signal "GND")
		(6 "In2.Cu" signal "IN1")
		(8 "In3.Cu" signal "GND1")
		(10 "In4.Cu" signal "IN2")
		(12 "In5.Cu" signal "GND2")
		(14 "In6.Cu" signal "IN3")
		(16 "In7.Cu" signal "GND3")
		(18 "In8.Cu" signal "VCC")
		(20 "In9.Cu" signal "VCC1")
		(22 "In10.Cu" signal "GND4")
		(24 "In11.Cu" signal "IN4")
		(26 "In12.Cu" signal "GND5")
		(28 "In13.Cu" signal "IN5")
		(30 "In14.Cu" signal "GND6")
		(32 "In15.Cu" signal "IN6")
		(34 "In16.Cu" signal "GND7")
		(2 "B.Cu" signal "BOTTOM")
		(9 "F.Adhes" user "F.Adhesive")
		(11 "B.Adhes" user "B.Adhesive")
		(13 "F.Paste" user "Package Geometry/Pastemask Top")
		(15 "B.Paste" user "Package Geometry/Pastemask Bottom")
		(5 "F.SilkS" user "Ref Des/Silkscreen Top")
		(7 "B.SilkS" user "Ref Des/Silkscreen Bottom")
		(1 "F.Mask" user "Board Geometry/Soldermask Top")
		(3 "B.Mask" user "Board Geometry/Soldermask Bottom")
		(17 "Dwgs.User" user "User.Drawings")
		(19 "Cmts.User" user "User.Comments")
		(21 "Eco1.User" user "User.Eco1")
		(23 "Eco2.User" user "User.Eco2")
		(25 "Edge.Cuts" user "Board Geometry/Outline")
		(27 "Margin" user)
		(31 "F.CrtYd" user "Package Geometry/Place Bound Top")
		(29 "B.CrtYd" user "Package Geometry/Place Bound Bottom")
		(35 "F.Fab" user "Ref Des/Assembly Top")
		(33 "B.Fab" user "Ref Des/Assembly Bottom")
	)
	(footprint ""
		(layer "F.Cu")
		(at 367.227358 -92.962984 -90)
		(property "Reference" "R2514"
			(at 0 0 270)
			(layer "F.SilkS")
			(hide yes)
			(effects
				(font
					(size 1.27 1.27)
				)
			)
		)
		(property "Value" ""
			(at 0 0 270)
			(layer "F.Fab")
			(effects
				(font
					(size 1.27 1.27)
				)
			)
		)
		(duplicate_pad_numbers_are_jumpers no)
		(fp_line
			(start -0.7874 0.4064)
			(end -0.7874 -0.4064)
			(stroke
				(width 0.1524)
				(type default)
			)
			(layer "F.SilkS")
		)
		(fp_line
			(start 0.7874 0.4064)
			(end -0.7874 0.4064)
			(stroke
				(width 0.1524)
				(type default)
			)
			(layer "F.SilkS")
		)
		(fp_line
			(start -0.7874 -0.4064)
			(end 0.7874 -0.4064)
			(stroke
				(width 0.1524)
				(type default)
			)
			(layer "F.SilkS")
		)
		(fp_line
			(start 0.7874 -0.4064)
			(end 0.7874 0.4064)
			(stroke
				(width 0.1524)
				(type default)
			)
			(layer "F.SilkS")
		)
		(fp_line
			(start -0.67945 0.3048)
			(end -0.67945 -0.305054)
			(stroke
				(width 0.1)
				(type default)
			)
			(layer "F.Fab")
		)
		(fp_line
			(start -0.12065 0.3048)
			(end -0.67945 0.3048)
			(stroke
				(width 0.1)
				(type default)
			)
			(layer "F.Fab")
		)
		(fp_line
			(start 0.120396 0.3048)
			(end 0.120396 0.2794)
			(stroke
				(width 0.1)
				(type default)
			)
			(layer "F.Fab")
		)
		(fp_line
			(start 0.67945 0.3048)
			(end 0.120396 0.3048)
			(stroke
				(width 0.1)
				(type default)
			)
			(layer "F.Fab")
		)
		(fp_line
			(start -0.12065 0.2794)
			(end -0.12065 0.3048)
			(stroke
				(width 0.1)
				(type default)
			)
			(layer "F.Fab")
		)
		(fp_line
			(start 0.120396 0.2794)
			(end -0.12065 0.2794)
			(stroke
				(width 0.1)
				(type default)
			)
			(layer "F.Fab")
		)
		(fp_line
			(start -0.12065 -0.2794)
			(end 0.12065 -0.2794)
			(stroke
				(width 0.1)
				(type default)
			)
			(layer "F.Fab")
		)
		(fp_line
			(start 0.12065 -0.2794)
			(end 0.12065 -0.3048)
			(stroke
				(width 0.1)
				(type default)
			)
			(layer "F.Fab")
		)
		(fp_line
			(start 0.12065 -0.3048)
			(end 0.67945 -0.3048)
			(stroke
				(width 0.1)
				(type default)
			)
			(layer "F.Fab")
		)
		(fp_line
			(start 0.67945 -0.3048)
			(end 0.67945 0.3048)
			(stroke
				(width 0.1)
				(type default)
			)
			(layer "F.Fab")
		)
		(fp_line
			(start -0.67945 -0.305054)
			(end -0.12065 -0.305054)
			(stroke
				(width 0.1)
				(type default)
			)
			(layer "F.Fab")
		)
		(fp_line
			(start -0.12065 -0.305054)
			(end -0.12065 -0.2794)
			(stroke
				(width 0.1)
				(type default)
			)
			(layer "F.Fab")
		)
		(pad "1" smd circle
			(at -0.40005 0 270)
			(size 0 0)
			(layers "F.Cu" "F.Mask" "F.Paste")
			(net "PU_GTL2014_BMC_JTAG_DIR_1")
		)
		(pad "2" smd circle
			(at 0.40005 0 270)
			(size 0 0)
			(layers "F.Cu" "F.Mask" "F.Paste")
			(net "GND")
		)
	)
	(footprint ""
		(layer "F.Cu")
		(at 53.08473 -17.623536 90)
		(property "Reference" "C833"
			(at 0 0 90)
			(layer "F.SilkS")
			(hide yes)
			(effects
				(font
					(size 1.27 1.27)
				)
			)
		)
		(property "Value" ""
			(at 0 0 90)
			(layer "F.Fab")
			(effects
				(font
					(size 1.27 1.27)
				)
			)
		)
		(duplicate_pad_numbers_are_jumpers no)
		(fp_line
			(start 0.299974 -0.150114)
			(end 0.299974 0.150114)
			(stroke
				(width 0.1)
				(type default)
			)
			(layer "F.Fab")
		)
		(fp_line
			(start -0.299974 -0.150114)
			(end 0.299974 -0.150114)
			(stroke
				(width 0.1)
				(type default)
			)
			(layer "F.Fab")
		)
		(fp_line
			(start 0.299974 0.150114)
			(end -0.299974 0.150114)
			(stroke
				(width 0.1)
				(type default)
			)
			(layer "F.Fab")
		)
		(fp_line
			(start -0.299974 0.150114)
			(end -0.299974 -0.150114)
			(stroke
				(width 0.1)
				(type default)
			)
			(layer "F.Fab")
		)
		(pad "1" smd rect
			(at -0.2667 0 90)
			(size 0.3048 0.381)
			(layers "F.Cu" "F.Mask" "F.Paste")
			(net "P5E_CPU1_PE1_TX_C_DP<2>")
		)
		(pad "2" smd rect
			(at 0.2667 0 90)
			(size 0.3048 0.381)
			(layers "F.Cu" "F.Mask" "F.Paste")
			(net "P5E_CPU1_PE1_TX_DP<2>")
		)
	)
	(footprint ""
		(layer "F.Cu")
		(at 456.520804 -76.588112 90)
		(property "Reference" "PC576"
			(at 0 0 90)
			(layer "F.SilkS")
			(hide yes)
			(effects
				(font
					(size 1.27 1.27)
				)
			)
		)
		(property "Value" ""
			(at 0 0 90)
			(layer "F.Fab")
			(effects
				(font
					(size 1.27 1.27)
				)
			)
		)
		(duplicate_pad_numbers_are_jumpers no)
		(fp_line
			(start 1.524 -0.762)
			(end 1.524 0.762)
			(stroke
				(width 0.1524)
				(type default)
			)
			(layer "F.SilkS")
		)
		(fp_line
			(start -1.524 -0.762)
			(end 1.524 -0.762)
			(stroke
				(width 0.1524)
				(type default)
			)
			(layer "F.SilkS")
		)
		(fp_line
			(start 1.524 0.762)
			(end -1.524 0.762)
			(stroke
				(width 0.1524)
				(type default)
			)
			(layer "F.SilkS")
		)
		(fp_line
			(start -1.524 0.762)
			(end -1.524 -0.762)
			(stroke
				(width 0.1524)
				(type default)
			)
			(layer "F.SilkS")
		)
		(fp_line
			(start 1.1049 -0.724916)
			(end -1.1049 -0.724916)
			(stroke
				(width 0.1)
				(type default)
			)
			(layer "F.Fab")
		)
		(fp_line
			(start -1.1049 -0.724916)
			(end -1.1049 0.724916)
			(stroke
				(width 0.1)
				(type default)
			)
			(layer "F.Fab")
		)
		(fp_line
			(start 1.1049 0.724916)
			(end 1.1049 -0.724916)
			(stroke
				(width 0.1)
				(type default)
			)
			(layer "F.Fab")
		)
		(fp_line
			(start -1.1049 0.724916)
			(end 1.1049 0.724916)
			(stroke
				(width 0.1)
				(type default)
			)
			(layer "F.Fab")
		)
		(pad "1" smd rect
			(at -0.889 0 270)
			(size 1.016 1.27)
			(layers "F.Cu" "F.Mask" "F.Paste")
			(net "SW_P3V3_AUX_FLT")
		)
		(pad "2" smd rect
			(at 0.889 0 270)
			(size 1.016 1.27)
			(layers "F.Cu" "F.Mask" "F.Paste")
			(net "GND")
		)
	)
	(footprint ""
		(layer "F.Cu")
		(at 184.290208 -407.439622 90)
		(property "Reference" "PC2189"
			(at 0 0 90)
			(layer "F.SilkS")
			(hide yes)
			(effects
				(font
					(size 1.27 1.27)
				)
			)
		)
		(property "Value" ""
			(at 0 0 90)
			(layer "F.Fab")
			(effects
				(font
					(size 1.27 1.27)
				)
			)
		)
		(duplicate_pad_numbers_are_jumpers no)
		(fp_line
			(start 0.7874 -0.4064)
			(end 0.7874 0.4064)
			(stroke
				(width 0.1524)
				(type default)
			)
			(layer "F.SilkS")
		)
		(fp_line
			(start -0.7874 -0.4064)
			(end 0.7874 -0.4064)
			(stroke
				(width 0.1524)
				(type default)
			)
			(layer "F.SilkS")
		)
		(fp_line
			(start 0.7874 0.4064)
			(end -0.7874 0.4064)
			(stroke
				(width 0.1524)
				(type default)
			)
			(layer "F.SilkS")
		)
		(fp_line
			(start -0.7874 0.4064)
			(end -0.7874 -0.4064)
			(stroke
				(width 0.1524)
				(type default)
			)
			(layer "F.SilkS")
		)
		(fp_line
			(start -0.12065 -0.305054)
			(end -0.12065 -0.2794)
			(stroke
				(width 0.1)
				(type default)
			)
			(layer "F.Fab")
		)
		(fp_line
			(start -0.67945 -0.305054)
			(end -0.12065 -0.305054)
			(stroke
				(width 0.1)
				(type default)
			)
			(layer "F.Fab")
		)
		(fp_line
			(start 0.67945 -0.3048)
			(end 0.67945 0.3048)
			(stroke
				(width 0.1)
				(type default)
			)
			(layer "F.Fab")
		)
		(fp_line
			(start 0.12065 -0.3048)
			(end 0.67945 -0.3048)
			(stroke
				(width 0.1)
				(type default)
			)
			(layer "F.Fab")
		)
		(fp_line
			(start 0.12065 -0.2794)
			(end 0.12065 -0.3048)
			(stroke
				(width 0.1)
				(type default)
			)
			(layer "F.Fab")
		)
		(fp_line
			(start -0.12065 -0.2794)
			(end 0.12065 -0.2794)
			(stroke
				(width 0.1)
				(type default)
			)
			(layer "F.Fab")
		)
		(fp_line
			(start 0.120396 0.2794)
			(end -0.12065 0.2794)
			(stroke
				(width 0.1)
				(type default)
			)
			(layer "F.Fab")
		)
		(fp_line
			(start -0.12065 0.2794)
			(end -0.12065 0.3048)
			(stroke
				(width 0.1)
				(type default)
			)
			(layer "F.Fab")
		)
		(fp_line
			(start 0.67945 0.3048)
			(end 0.120396 0.3048)
			(stroke
				(width 0.1)
				(type default)
			)
			(layer "F.Fab")
		)
		(fp_line
			(start 0.120396 0.3048)
			(end 0.120396 0.2794)
			(stroke
				(width 0.1)
				(type default)
			)
			(layer "F.Fab")
		)
		(fp_line
			(start -0.12065 0.3048)
			(end -0.67945 0.3048)
			(stroke
				(width 0.1)
				(type default)
			)
			(layer "F.Fab")
		)
		(fp_line
			(start -0.67945 0.3048)
			(end -0.67945 -0.305054)
			(stroke
				(width 0.1)
				(type default)
			)
			(layer "F.Fab")
		)
		(pad "1" smd circle
			(at -0.40005 0 90)
			(size 0 0)
			(layers "F.Cu" "F.Mask" "F.Paste")
			(net "HSC_VSENSE")
		)
		(pad "2" smd circle
			(at 0.40005 0 90)
			(size 0 0)
			(layers "F.Cu" "F.Mask" "F.Paste")
			(net "AGND_HSC")
		)
	)
	(footprint ""
		(layer "F.Cu")
		(at 305.58994 -433.0573 90)
		(property "Reference" "R4135"
			(at 0 0 90)
			(layer "F.SilkS")
			(hide yes)
			(effects
				(font
					(size 1.27 1.27)
				)
			)
		)
		(property "Value" ""
			(at 0 0 90)
			(layer "F.Fab")
			(effects
				(font
					(size 1.27 1.27)
				)
			)
		)
		(duplicate_pad_numbers_are_jumpers no)
		(fp_line
			(start 0.7874 -0.4064)
			(end 0.7874 0.4064)
			(stroke
				(width 0.1524)
				(type default)
			)
			(layer "F.SilkS")
		)
		(fp_line
			(start -0.7874 -0.4064)
			(end 0.7874 -0.4064)
			(stroke
				(width 0.1524)
				(type default)
			)
			(layer "F.SilkS")
		)
		(fp_line
			(start 0.7874 0.4064)
			(end -0.7874 0.4064)
			(stroke
				(width 0.1524)
				(type default)
			)
			(layer "F.SilkS")
		)
		(fp_line
			(start -0.7874 0.4064)
			(end -0.7874 -0.4064)
			(stroke
				(width 0.1524)
				(type default)
			)
			(layer "F.SilkS")
		)
		(fp_line
			(start -0.12065 -0.305054)
			(end -0.12065 -0.2794)
			(stroke
				(width 0.1)
				(type default)
			)
			(layer "F.Fab")
		)
		(fp_line
			(start -0.67945 -0.305054)
			(end -0.12065 -0.305054)
			(stroke
				(width 0.1)
				(type default)
			)
			(layer "F.Fab")
		)
		(fp_line
			(start 0.67945 -0.3048)
			(end 0.67945 0.3048)
			(stroke
				(width 0.1)
				(type default)
			)
			(layer "F.Fab")
		)
		(fp_line
			(start 0.12065 -0.3048)
			(end 0.67945 -0.3048)
			(stroke
				(width 0.1)
				(type default)
			)
			(layer "F.Fab")
		)
		(fp_line
			(start 0.12065 -0.2794)
			(end 0.12065 -0.3048)
			(stroke
				(width 0.1)
				(type default)
			)
			(layer "F.Fab")
		)
		(fp_line
			(start -0.12065 -0.2794)
			(end 0.12065 -0.2794)
			(stroke
				(width 0.1)
				(type default)
			)
			(layer "F.Fab")
		)
		(fp_line
			(start 0.120396 0.2794)
			(end -0.12065 0.2794)
			(stroke
				(width 0.1)
				(type default)
			)
			(layer "F.Fab")
		)
		(fp_line
			(start -0.12065 0.2794)
			(end -0.12065 0.3048)
			(stroke
				(width 0.1)
				(type default)
			)
			(layer "F.Fab")
		)
		(fp_line
			(start 0.67945 0.3048)
			(end 0.120396 0.3048)
			(stroke
				(width 0.1)
				(type default)
			)
			(layer "F.Fab")
		)
		(fp_line
			(start 0.120396 0.3048)
			(end 0.120396 0.2794)
			(stroke
				(width 0.1)
				(type default)
			)
			(layer "F.Fab")
		)
		(fp_line
			(start -0.12065 0.3048)
			(end -0.67945 0.3048)
			(stroke
				(width 0.1)
				(type default)
			)
			(layer "F.Fab")
		)
		(fp_line
			(start -0.67945 0.3048)
			(end -0.67945 -0.305054)
			(stroke
				(width 0.1)
				(type default)
			)
			(layer "F.Fab")
		)
		(pad "1" smd circle
			(at -0.40005 0 90)
			(size 0 0)
			(layers "F.Cu" "F.Mask" "F.Paste")
			(net "P3V3_AUX")
		)
		(pad "2" smd circle
			(at 0.40005 0 90)
			(size 0 0)
			(layers "F.Cu" "F.Mask" "F.Paste")
			(net "PRSNT_CABLE_GPU_A2_N")
		)
	)
	(footprint ""
		(layer "F.Cu")
		(at 126.635002 -154.195018 90)
		(property "Reference" "JP15"
			(at 9.14146 0.288798 0)
			(unlocked yes)
			(layer "F.SilkS")
			(effects
				(font
					(size 0.7874 0.5842)
					(thickness 0.1524)
				)
				(justify left)
			)
		)
		(property "Value" ""
			(at 0 0 90)
			(layer "F.Fab")
			(effects
				(font
					(size 1.27 1.27)
				)
			)
		)
		(duplicate_pad_numbers_are_jumpers no)
		(fp_line
			(start 1.249934 -1.320038)
			(end 1.249934 6.400038)
			(stroke
				(width 0.1524)
				(type default)
			)
			(layer "F.SilkS")
		)
		(fp_line
			(start -1.249934 -1.320038)
			(end 1.249934 -1.320038)
			(stroke
				(width 0.1524)
				(type default)
			)
			(layer "F.SilkS")
		)
		(fp_line
			(start 1.249934 6.400038)
			(end -1.249934 6.400038)
			(stroke
				(width 0.1524)
				(type default)
			)
			(layer "F.SilkS")
		)
		(fp_line
			(start -1.249934 6.400038)
			(end -1.249934 -1.320038)
			(stroke
				(width 0.1524)
				(type default)
			)
			(layer "F.SilkS")
		)
		(fp_poly
			(pts
				(xy -2.5654 -0.556514) (xy -1.452372 0) (xy -2.5654 0.556514)
			)
			(stroke
				(width 0)
				(type default)
			)
			(fill yes)
			(layer "F.SilkS")
		)
		(fp_line
			(start 1.249934 -1.320038)
			(end 1.249934 6.400038)
			(stroke
				(width 0.1)
				(type default)
			)
			(layer "F.Fab")
		)
		(fp_line
			(start -1.249934 -1.320038)
			(end 1.249934 -1.320038)
			(stroke
				(width 0.1)
				(type default)
			)
			(layer "F.Fab")
		)
		(fp_line
			(start 1.249934 6.400038)
			(end -1.249934 6.400038)
			(stroke
				(width 0.1)
				(type default)
			)
			(layer "F.Fab")
		)
		(fp_line
			(start -1.249934 6.400038)
			(end -1.249934 -1.320038)
			(stroke
				(width 0.1)
				(type default)
			)
			(layer "F.Fab")
		)
		(fp_poly
			(pts
				(xy -2.5654 -0.556514) (xy -1.452372 0) (xy -2.5654 0.556514)
			)
			(stroke
				(width 0)
				(type default)
			)
			(fill yes)
			(layer "F.Fab")
		)
		(fp_text user "3"
			(at -1.778 5.13207 90)
			(unlocked yes)
			(layer "F.SilkS")
			(effects
				(font
					(size 0.7874 0.5842)
					(thickness 0.1524)
				)
			)
		)
		(fp_text user "1"
			(at -1.143 0.02667 90)
			(unlocked yes)
			(layer "B.SilkS")
			(effects
				(font
					(size 0.7874 0.5842)
					(thickness 0.1524)
				)
				(justify mirror)
			)
		)
		(fp_text user "3"
			(at -1.1557 5.18287 90)
			(unlocked yes)
			(layer "B.SilkS")
			(effects
				(font
					(size 0.7874 0.5842)
					(thickness 0.1524)
				)
				(justify mirror)
			)
		)
		(fp_text user "1"
			(at -1.143 0.02667 90)
			(unlocked yes)
			(layer "B.Fab")
			(effects
				(font
					(size 0.7874 0.5842)
					(thickness 0.1524)
				)
				(justify mirror)
			)
		)
		(fp_text user "3"
			(at -1.1557 5.18287 90)
			(unlocked yes)
			(layer "B.Fab")
			(effects
				(font
					(size 0.7874 0.5842)
					(thickness 0.1524)
				)
				(justify mirror)
			)
		)
		(fp_text user "3"
			(at -1.778 5.13207 90)
			(unlocked yes)
			(layer "F.Fab")
			(effects
				(font
					(size 0.7874 0.5842)
					(thickness 0.1524)
				)
			)
		)
		(pad "1" thru_hole rect
			(at 0 0 90)
			(size 1.5494 1.5494)
			(drill 1.0414)
			(layers "*.Cu" "*.Mask")
			(remove_unused_layers no)
			(net "PU_FORCE_PWRON")
			(clearance 0)
			(padstack
				(mode front_inner_back)
				(layer "Inner"
					(shape circle)
					(size 1.5494 1.5494)
					(clearance 0)
				)
				(layer "B.Cu"
					(shape rect)
					(size 1.5494 1.5494)
					(clearance 0)
				)
			)
		)
		(pad "2" thru_hole circle
			(at 0 2.54 90)
			(size 1.5494 1.5494)
			(drill 1.0414)
			(layers "*.Cu" "*.Mask")
			(remove_unused_layers no)
			(net "FM_FORCE_PWRON_LVC3")
			(clearance 0)
		)
		(pad "3" thru_hole circle
			(at 0 5.08 90)
			(size 1.5494 1.5494)
			(drill 1.0414)
			(layers "*.Cu" "*.Mask")
			(remove_unused_layers no)
			(net "PD_FORCE_PWRON")
			(clearance 0)
		)
	)
	(footprint ""
		(layer "F.Cu")
		(at 209.149696 -67.853306)
		(property "Reference" "Q150"
			(at -1.4478 2.016252 0)
			(unlocked yes)
			(layer "F.SilkS")
			(effects
				(font
					(size 0.7874 0.5842)
					(thickness 0.1524)
				)
				(justify left)
			)
		)
		(property "Value" ""
			(at 0 0 0)
			(layer "F.Fab")
			(effects
				(font
					(size 1.27 1.27)
				)
			)
		)
		(duplicate_pad_numbers_are_jumpers no)
		(fp_line
			(start -1.332738 -1.100074)
			(end -0.4826 -1.100074)
			(stroke
				(width 0.1524)
				(type default)
			)
			(layer "F.SilkS")
		)
		(fp_line
			(start -1.332738 1.100074)
			(end -1.332738 -1.100074)
			(stroke
				(width 0.1524)
				(type default)
			)
			(layer "F.SilkS")
		)
		(fp_line
			(start -0.4826 -1.100074)
			(end 0 -0.541274)
			(stroke
				(width 0.1524)
				(type default)
			)
			(layer "F.SilkS")
		)
		(fp_line
			(start 0 -0.541274)
			(end 0.4826 -1.100074)
			(stroke
				(width 0.1524)
				(type default)
			)
			(layer "F.SilkS")
		)
		(fp_line
			(start 0.4826 -1.100074)
			(end 1.332738 -1.100074)
			(stroke
				(width 0.1524)
				(type default)
			)
			(layer "F.SilkS")
		)
		(fp_line
			(start 1.332738 -1.100074)
			(end 1.332738 1.100074)
			(stroke
				(width 0.1524)
				(type default)
			)
			(layer "F.SilkS")
		)
		(fp_line
			(start 1.332738 1.100074)
			(end -1.332738 1.100074)
			(stroke
				(width 0.1524)
				(type default)
			)
			(layer "F.SilkS")
		)
		(fp_poly
			(pts
				(xy -2.2352 -0.298958) (xy -2.2352 -1.001014) (xy -1.533144 -0.649986)
			)
			(stroke
				(width 0)
				(type default)
			)
			(fill yes)
			(layer "F.SilkS")
		)
		(fp_line
			(start -0.674878 -1.100074)
			(end 0.674878 -1.100074)
			(stroke
				(width 0.1)
				(type default)
			)
			(layer "F.Fab")
		)
		(fp_line
			(start -0.674878 1.100074)
			(end -0.674878 -1.100074)
			(stroke
				(width 0.1)
				(type default)
			)
			(layer "F.Fab")
		)
		(fp_line
			(start 0.674878 -1.100074)
			(end 0.674878 1.100074)
			(stroke
				(width 0.1)
				(type default)
			)
			(layer "F.Fab")
		)
		(fp_line
			(start 0.674878 1.100074)
			(end -0.674878 1.100074)
			(stroke
				(width 0.1)
				(type default)
			)
			(layer "F.Fab")
		)
		(fp_poly
			(pts
				(xy -2.2352 -0.298958) (xy -2.2352 -1.001014) (xy -1.533144 -0.649986)
			)
			(stroke
				(width 0)
				(type default)
			)
			(fill yes)
			(layer "F.Fab")
		)
		(pad "1" smd rect
			(at -0.94996 -0.649986 90)
			(size 0.4318 0.508)
			(layers "F.Cu" "F.Mask" "F.Paste")
			(net "GND")
		)
		(pad "2" smd rect
			(at -0.94996 0 90)
			(size 0.4318 0.508)
			(layers "F.Cu" "F.Mask" "F.Paste")
			(net "P12V_SCM_FAULT_R_N")
		)
		(pad "3" smd rect
			(at -0.94996 0.649986 90)
			(size 0.4318 0.508)
			(layers "F.Cu" "F.Mask" "F.Paste")
			(net "LED_P12V_SCM_FAULT_D2")
		)
		(pad "4" smd rect
			(at 0.94996 0.649986 90)
			(size 0.4318 0.508)
			(layers "F.Cu" "F.Mask" "F.Paste")
			(net "GND")
		)
		(pad "5" smd rect
			(at 0.94996 0 90)
			(size 0.4318 0.508)
			(layers "F.Cu" "F.Mask" "F.Paste")
			(net "LED_P12V_SCM_FAULT_D1")
		)
		(pad "6" smd rect
			(at 0.94996 -0.649986 90)
			(size 0.4318 0.508)
			(layers "F.Cu" "F.Mask" "F.Paste")
			(net "LED_P12V_SCM_FAULT_D1")
		)
	)
)
